FILE_TYPE = CONNECTIVITY;
{Allegro Design Entry HDL 17.2-2016 S081 (4005846) 1/11/2022}
"PAGE_NUMBER" = 50;
0"NC";
1"P3V3_RTC_AUX\g";
2"P3V3_AUX\g";
3"P3V3_AUX\g";
4"P3V3_AUX\g";
5"P3V3_AUX\g";
6"P3V3_AUX\g";
7"P3V3_AUX\g";
8"P12V_AUX\g";
9"P5V_AUX\g";
10"P3V3_AUX\g";
11"P3V3_AUX\g";
12"P3V3_AUX\g";
13"GND\g";
14"GND\g";
15"GND\g";
16"GND\g";
17"GND\g";
18"GND\g";
19"GND\g";
20"GND\g";
21"GND\g";
22"GND\g";
23"GND\g";
24"GND\g";
25"GND\g";
26"GND\g";
27"GND\g";
28"GND\g";
29"GND\g";
30"REAR_AC_PWR_BTN";
31"REAR_AC_PWR_BMC_BTN_N";
32"TP_ID_BUF";
33"LED_D22_R1";
34"LED_D22_R";
35"LED_D21_R3";
36"FM_DEBUG_RST_BTN_N";
37"REAR_PWR_BTN_N";
38"REAR_ID_RST_BTN_N";
39"AC_PWR_BMC_BTN_N";
40"NC_U57_P1";
41"LED_D21_R1";
42"ID_RST_BTN_BMC_N";
43"REAR_AC_PWR_BTN_N";
44"LED_D21_R2";
45"AC_PWR_BTN_N";
46"AC_PWR_BTN_R1_N";
47"NC_U16_P1";
48"P3V_BAT_R";
49"PWRGD_P1V0_AUX_DELAY";
50"PWR_BTN_BMC_N";
51"TP_PWR_BUF";
52"FM_DEBUG_PWR_BTN_N";
%"UNIVERSAL_GND"
"1","(-3175,2925)","0","logical_power","I138";
;
CDS_LIB"logical_power"
HDL_POWER"GND";
"A"24;
%"74LVC1G07GW"
"1","(-125,4650)","0","pure_quanta","I151";
;
VALUE"74LVC1G07GW"
PART_TYPE"SMLF"
PART_NUMBER"ALVC1G07002"
MATERIAL"IC"
SEC_TYPE""
CDS_LMAN_SYM_OUTLINE"-150,150,150,-150"
CDS_LIB"pure_quanta"
LOCATION"U31"
SEC"1";
"NC"
$PN"1"51;
"Y"
$PN"4"50;
"GND"
$PN"3"28;
"A"
$PN"2"37;
"VCC"
$PN"5"3;
%"Q_RES"
"1","(-2000,5175)","2","pure_quanta","I152";
;
MATERIAL"CHIP"
VALUE"0"
PACK_TYPE"0402LF"
WATTAGE"1/16W"
TOLERANCE"5%"
PART_NUMBER"CS00002JB13"
CDS_LIB"pure_quanta"
LOCATION"R734"
$SEC"1"
CDS_SEC"1";
"B"
$PN"2"52;
"A"
$PN"1"37;
%"Q_RES"
"1","(-2200,3775)","2","pure_quanta","I154";
;
MATERIAL"CHIP"
VALUE"0"
PACK_TYPE"0402LF"
WATTAGE"1/16W"
TOLERANCE"5%"
PART_NUMBER"CS00002JB13"
CDS_LIB"pure_quanta"
LOCATION"R733"
$SEC"1"
CDS_SEC"1";
"B"
$PN"2"36;
"A"
$PN"1"38;
%"BAS70057F"
"1","(3975,4950)","7","pure_quanta","I161";
;
PART_TYPE"SMLF"
PART_NUMBER"BC0BAS70Z01"
VALUE"BAS70-05-7-F"
MATERIAL"IC"
SEC_TYPE""
CDS_LMAN_SYM_OUTLINE"-75,50,75,-25"
NEEDS_NO_SIZE"TRUE"
CDS_LIB"pure_quanta"
LOCATION"U48"
SEC"1";
"C"
$PN"3"1;
"A"
$PN"2"2;
"B"
$PN"1"48;
%"VCCAUX15"
"1","(3300,5300)","0","logical_power","I163";
;
HDL_POWER"P3V3_AUX"
CDS_LIB"logical_power";
"A"2;
%"UNIVERSAL_POWER"
"1","(4650,5275)","0","logical_power","I164";
;
HDL_POWER"P3V3_RTC_AUX"
CDS_LIB"logical_power";
"A"1;
%"Q_CAP"
"1","(4650,4700)","0","pure_quanta","I165";
;
PART_NUMBER"CH5104KEB02"
MATERIAL"X6S"
TOLERANCE"10%"
VOLTAGE"25V"
VALUE"1UF"
PACK_TYPE"C0402"
CDS_LIB"pure_quanta"
LOCATION"C196"
$SEC"1"
CDS_SEC"1";
"B"
$PN"2"29;
"A"
$PN"1"1;
%"UNIVERSAL_GND"
"1","(4650,4375)","0","logical_power","I166";
;
HDL_POWER"GND"
CDS_LIB"logical_power";
"A"29;
%"UNIVERSAL_GND"
"1","(-3025,4325)","0","logical_power","I169";
;
HDL_POWER"GND"
CDS_LIB"logical_power";
"A"27;
%"UNIVERSAL_GND"
"1","(-1400,2650)","0","logical_power","I192";
;
HDL_POWER"GND"
CDS_LIB"logical_power";
"A"23;
%"SW_PUSHBUTTON4P_12_G34_H2"
"1","(-2850,3350)","0","pure_quanta","I204";
;
PART_NUMBER"DHPDTSAM601"
MATERIAL"MECH"
PART_TYPE"SMLF"
VALUE"SW4S_DTSAM-63N/K-S-Q-T/R"
NEEDS_NO_SIZE"TRUE"
CDS_LMAN_SYM_OUTLINE"-75,100,75,-100"
CDS_LIB"pure_quanta"
LOCATION"SW7"
$SEC"1"
CDS_SEC"1";
"4"
$PN"4"24;
"3"
$PN"3"24;
"2 \B"
$PN"2"38;
"1 \B"
$PN"1"24;
%"UNIVERSAL_GND"
"1","(750,-525)","0","logical_power","I208";
;
HDL_POWER"GND"
CDS_LIB"logical_power";
"A"21;
%"Q_RES"
"1","(750,800)","1","pure_quanta","I210";
;
WATTAGE"1/16W"
PACK_TYPE"0402LF"
MATERIAL"CHIP"
PART_NUMBER"CS12202FB04"
VALUE"220"
TOLERANCE"1%"
CDS_LIB"pure_quanta"
$LOCATION"R80"
CDS_LOCATION"R80"
$SEC"1"
CDS_SEC"1";
"B"
$PN"2"9;
"A"
$PN"1"34;
%"UNIVERSAL_POWER"
"1","(750,1175)","0","logical_power","I211";
;
HDL_POWER"P5V_AUX"
CDS_LIB"logical_power";
"A"9;
%"Q_CAP"
"1","(750,-200)","0","pure_quanta","I212";
;
PART_NUMBER"CH4104K1B00"
MATERIAL"X7R"
TOLERANCE"10%"
PACK_TYPE"0402"
VALUE"0.1UF"
VOLTAGE"25V"
CDS_LIB"pure_quanta"
$LOCATION"C27"
CDS_LOCATION"C27"
$SEC"1"
CDS_SEC"1";
"B"
$PN"2"21;
"A"
$PN"1"34;
%"UNIVERSAL_GND"
"1","(-1575,-625)","0","logical_power","I217";
;
CDS_LIB"logical_power"
HDL_POWER"GND";
"A"20;
%"MOSFET_NCH_DUAL"
"1","(-1625,-275)","0","pure_quanta","I218";
;
VALUE"PJT138K"
PART_TYPE"SMLF"
PART_NUMBER"BAM138K0003"
MATERIAL"IC"
CDS_LMAN_SYM_OUTLINE"-150,150,150,-150"
NEEDS_NO_SIZE"TRUE"
CDS_LIB"pure_quanta"
$LOCATION"Q13"
CDS_LOCATION"Q13"
$SEC"1"
CDS_SEC"1";
"D1"
$PN"6"33;
"G1"
$PN"2"49;
"S1"
$PN"1"20;
%"UNIVERSAL_POWER"
"1","(950,2200)","0","logical_power","I220";
;
HDL_POWER"P12V_AUX"
CDS_LIB"logical_power";
"A"8;
%"Q_RES"
"1","(-750,1625)","0","pure_quanta","I222";
;
WATTAGE"1/16W"
PACK_TYPE"0402LF"
PART_NUMBER"CS13162FB01"
VALUE"316"
TOLERANCE"1%"
MATERIAL"CHIP"
CDS_LIB"pure_quanta"
$LOCATION"R107"
CDS_LOCATION"R107"
$SEC"1"
CDS_SEC"1";
"B"
$PN"2"44;
"A"
$PN"1"35;
%"Q_RES"
"1","(-25,1625)","0","pure_quanta","I224";
;
PACK_TYPE"0402LF"
MATERIAL"CHIP"
VALUE"316"
WATTAGE"1/16W"
PART_NUMBER"CS13162FB01"
TOLERANCE"1%"
CDS_LIB"pure_quanta"
$LOCATION"R286"
CDS_LOCATION"R286"
$SEC"1"
CDS_SEC"1";
"B"
$PN"2"41;
"A"
$PN"1"44;
%"Q_RES"
"1","(625,1625)","0","pure_quanta","I225";
;
PACK_TYPE"0402LF"
MATERIAL"CHIP"
WATTAGE"1/16W"
TOLERANCE"1%"
PART_NUMBER"CS13162FB01"
VALUE"316"
CDS_LIB"pure_quanta"
$LOCATION"R389"
CDS_LOCATION"R389"
$SEC"1"
CDS_SEC"1";
"B"
$PN"2"8;
"A"
$PN"1"41;
%"UNIVERSAL_GND"
"1","(-1825,1450)","0","logical_power","I226";
;
HDL_POWER"GND"
CDS_LIB"logical_power";
"A"22;
%"74LVC1G07GW"
"1","(4050,3275)","0","pure_quanta","I227";
;
VALUE"74LVC1G07GW"
PART_TYPE"SMLF"
PART_NUMBER"ALVC1G07002"
MATERIAL"EMPTY"
CDS_LIB"pure_quanta"
CDS_LMAN_SYM_OUTLINE"-150,150,150,-150"
SEC_TYPE""
$LOCATION"U16"
CDS_LOCATION"U16"
SEC"1";
"NC"
$PN"1"47;
"Y"
$PN"4"46;
"GND"
$PN"3"15;
"A"
$PN"2"43;
"VCC"
$PN"5"6;
%"VCCAUX15"
"1","(3700,3875)","0","logical_power","I231";
;
HDL_POWER"P3V3_AUX"
CDS_LIB"logical_power";
"A"6;
%"Q_CAP"
"1","(3700,3675)","2","pure_quanta","I232";
;
PACK_TYPE"0402"
PART_NUMBER"CH4104K1B00"
VALUE"0.1UF"
VOLTAGE"25V"
TOLERANCE"10%"
MATERIAL"EMPTY"
CDS_LIB"pure_quanta"
$LOCATION"C29"
CDS_LOCATION"C29"
$SEC"1"
CDS_SEC"1";
"B"
$PN"2"14;
"A"
$PN"1"6;
%"UNIVERSAL_GND"
"1","(3700,3450)","0","logical_power","I233";
;
CDS_LIB"logical_power"
HDL_POWER"GND";
"A"14;
%"VCCAUX15"
"1","(3000,3875)","0","logical_power","I234";
;
HDL_POWER"P3V3_AUX"
CDS_LIB"logical_power";
"A"5;
%"Q_RES"
"2","(3000,3675)","0","pure_quanta","I235";
;
PACK_TYPE"0402LF"
PART_NUMBER"CS28202JB05"
MATERIAL"EMPTY"
WATTAGE"1/16W"
TOLERANCE"5%"
VALUE"8.2K"
CDS_LIB"pure_quanta"
$LOCATION"R391"
CDS_LOCATION"R391"
$SEC"1"
CDS_SEC"1";
"A"
$PN"1"5;
"B"
$PN"2"43;
%"Q_CAP"
"1","(3000,3000)","0","pure_quanta","I236";
;
TOLERANCE"10%"
MATERIAL"EMPTY"
VOLTAGE"25V"
VALUE"1UF"
PACK_TYPE"C0402"
PART_NUMBER"CH5104KEB02"
CDS_LIB"pure_quanta"
$LOCATION"C28"
CDS_LOCATION"C28"
$SEC"1"
CDS_SEC"1";
"B"
$PN"2"15;
"A"
$PN"1"43;
%"UNIVERSAL_GND"
"1","(1600,2125)","0","logical_power","I238";
;
HDL_POWER"GND"
CDS_LIB"logical_power";
"A"19;
%"UNIVERSAL_GND"
"1","(2875,2650)","0","logical_power","I239";
;
HDL_POWER"GND"
CDS_LIB"logical_power";
"A"15;
%"Q_RES"
"1","(2675,3275)","0","pure_quanta","I241";
;
MATERIAL"EMPTY"
VALUE"0"
CDS_LIB"pure_quanta"
PACK_TYPE"0402LF"
WATTAGE"1/16W"
TOLERANCE"5%"
PART_NUMBER"CS00002JB13"
$LOCATION"R470"
CDS_LOCATION"R470"
$SEC"1"
CDS_SEC"1";
"B"
$PN"2"43;
"A"
$PN"1"30;
%"Q_RES"
"1","(4100,2550)","0","pure_quanta","I242";
;
VALUE"0"
MATERIAL"CHIP"
CDS_LIB"pure_quanta"
PART_NUMBER"CS00002JB13"
TOLERANCE"5%"
WATTAGE"1/16W"
PACK_TYPE"0402LF"
$LOCATION"R471"
CDS_LOCATION"R471"
$SEC"1"
CDS_SEC"1";
"B"
$PN"2"45;
"A"
$PN"1"30;
%"DIODE_BIDIRECTIONAL"
"1","(4100,2225)","0","pure_quanta","I244";
;
PART_NUMBER"BC00511TZ00"
MATERIAL"IC"
VALUE"UCLAMP0511T"
PART_TYPE"SMLF"
CDS_LMAN_SYM_OUTLINE"-100,50,100,-50"
NEEDS_NO_SIZE"TRUE"
CDS_LIB"pure_quanta"
$LOCATION"D10"
CDS_LOCATION"D10"
$SEC"1"
CDS_SEC"1";
"C"
Pin_Length"Short"
$PN"C"13;
"A"
$PN"A"30;
%"UNIVERSAL_GND"
"1","(4425,2075)","0","logical_power","I245";
;
HDL_POWER"GND"
CDS_LIB"logical_power";
"A"13;
%"Q_CAP"
"1","(3800,2075)","2","pure_quanta","I246";
;
PART_NUMBER"CH4104K1B00"
PACK_TYPE"0402"
VALUE"0.1UF"
VOLTAGE"25V"
TOLERANCE"10%"
MATERIAL"X7R"
CDS_LIB"pure_quanta"
$LOCATION"C181"
CDS_LOCATION"C181"
$SEC"1"
CDS_SEC"1";
"B"
$PN"2"16;
"A"
$PN"1"30;
%"UNIVERSAL_GND"
"1","(3800,1825)","0","logical_power","I247";
;
HDL_POWER"GND"
CDS_LIB"logical_power";
"A"16;
%"74LVC1G07GW"
"1","(4100,1050)","0","pure_quanta","I278";
;
VALUE"74LVC1G07GW"
PART_TYPE"SMLF"
PART_NUMBER"ALVC1G07002"
MATERIAL"IC"
CDS_LIB"pure_quanta"
CDS_LMAN_SYM_OUTLINE"-150,150,150,-150"
SEC_TYPE""
$LOCATION"U57"
CDS_LOCATION"U57"
SEC"1";
"NC"
$PN"1"40;
"Y"
$PN"4"39;
"GND"
$PN"3"18;
"A"
$PN"2"31;
"VCC"
$PN"5"11;
%"VCCAUX15"
"1","(3750,1650)","0","logical_power","I280";
;
HDL_POWER"P3V3_AUX"
CDS_LIB"logical_power";
"A"11;
%"Q_CAP"
"1","(3750,1450)","2","pure_quanta","I281";
;
PART_NUMBER"CH4104K1B00"
TOLERANCE"10%"
VOLTAGE"25V"
PACK_TYPE"0402"
MATERIAL"X7R"
VALUE"0.1UF"
CDS_LIB"pure_quanta"
$LOCATION"C336"
CDS_LOCATION"C336"
$SEC"1"
CDS_SEC"1";
"B"
$PN"2"17;
"A"
$PN"1"11;
%"UNIVERSAL_GND"
"1","(3750,1225)","0","logical_power","I282";
;
HDL_POWER"GND"
CDS_LIB"logical_power";
"A"17;
%"VCCAUX15"
"1","(2975,1650)","0","logical_power","I283";
;
HDL_POWER"P3V3_AUX"
CDS_LIB"logical_power";
"A"12;
%"Q_RES"
"2","(2975,1450)","0","pure_quanta","I284";
;
MATERIAL"EMPTY"
PART_NUMBER"CS28202JB05"
WATTAGE"1/16W"
PACK_TYPE"0402LF"
TOLERANCE"5%"
VALUE"8.2K"
CDS_LIB"pure_quanta"
$LOCATION"R883"
CDS_LOCATION"R883"
$SEC"1"
CDS_SEC"1";
"A"
$PN"1"12;
"B"
$PN"2"31;
%"Q_CAP"
"1","(3050,775)","0","pure_quanta","I285";
;
MATERIAL"X6S"
TOLERANCE"10%"
VOLTAGE"25V"
VALUE"1UF"
PACK_TYPE"C0402"
PART_NUMBER"CH5104KEB02"
CDS_LIB"pure_quanta"
$LOCATION"C335"
CDS_LOCATION"C335"
$SEC"1"
CDS_SEC"1";
"B"
$PN"2"18;
"A"
$PN"1"31;
%"Q_RES"
"1","(2650,1050)","0","pure_quanta","I286";
;
VALUE"0"
MATERIAL"CHIP"
CDS_LIB"pure_quanta"
PACK_TYPE"0402LF"
WATTAGE"1/16W"
TOLERANCE"5%"
PART_NUMBER"CS00002JB13"
$LOCATION"R882"
CDS_LOCATION"R882"
$SEC"1"
CDS_SEC"1";
"B"
$PN"2"31;
"A"
$PN"1"30;
%"UNIVERSAL_GND"
"1","(2925,425)","0","logical_power","I287";
;
CDS_LIB"logical_power"
HDL_POWER"GND";
"A"18;
%"SW_PUSHBUTTON4P_12_G34_H2"
"1","(-2700,4750)","0","pure_quanta","I292";
;
PART_NUMBER"DHPDTSAM601"
MATERIAL"MECH"
PART_TYPE"SMLF"
VALUE"SW4S_DTSAM-63N/K-S-Q-T/R"
CDS_LIB"pure_quanta"
CDS_LMAN_SYM_OUTLINE"-75,100,75,-100"
NEEDS_NO_SIZE"TRUE"
LOCATION"SW6"
$SEC"1"
CDS_SEC"1";
"4"
$PN"4"27;
"3"
$PN"3"27;
"2 \B"
$PN"2"37;
"1 \B"
$PN"1"27;
%"SW_PUSHBUTTON4P_12_G34_H2"
"1","(1925,2550)","0","pure_quanta","I293";
;
PART_NUMBER"DHPDTSAM601"
VALUE"SW4S_DTSAM-63N/K-S-Q-T/R"
MATERIAL"MECH"
PART_TYPE"SMLF"
CDS_LIB"pure_quanta"
CDS_LMAN_SYM_OUTLINE"-75,100,75,-100"
NEEDS_NO_SIZE"TRUE"
LOCATION"SW8"
$SEC"1"
CDS_SEC"1";
"4"
$PN"4"19;
"3"
$PN"3"19;
"2 \B"
$PN"2"30;
"1 \B"
$PN"1"19;
%"Q_LED"
"1","(-1500,1625)","2","pure_quanta","I294";
;
PART_NUMBER"BEBL0277D00"
MATERIAL"IC"
PACK_TYPE"THLF"
MANUF_PN"HV-312470/260/SUBD-TR1"
COLOR"LED_BLUE"
NEEDS_NO_SIZE"TRUE"
CDS_LIB"pure_quanta"
LOCATION"D21"
$SEC"1"
CDS_SEC"1";
"A"
$PN"A"35;
"C"
$PN"C"22;
%"Q_LED"
"1","(-550,100)","2","pure_quanta","I295";
;
PART_NUMBER"BEBL0277D00"
MATERIAL"IC"
PACK_TYPE"THLF"
MANUF_PN"HV-312470/260/SUBD-TR1"
COLOR"LED_BLUE"
CDS_LIB"pure_quanta"
NEEDS_NO_SIZE"TRUE"
LOCATION"D22"
$SEC"1"
CDS_SEC"1";
"A"
$PN"A"34;
"C"
$PN"C"33;
%"UNIVERSAL_GND"
"1","(-1300,4025)","0","logical_power","I30";
;
HDL_POWER"GND"
CDS_LIB"logical_power";
"A"28;
%"Q_CAP"
"1","(-475,5050)","2","pure_quanta","I43";
;
PART_NUMBER"CH4104K1B00"
PACK_TYPE"0402"
VALUE"0.1UF"
MATERIAL"X7R"
VOLTAGE"25V"
TOLERANCE"10%"
CDS_LIB"pure_quanta"
LOCATION"C200"
$SEC"1"
CDS_SEC"1";
"B"
$PN"2"26;
"A"
$PN"1"3;
%"Q_CAP"
"1","(-1175,4375)","0","pure_quanta","I44";
;
VALUE"1UF"
VOLTAGE"25V"
MATERIAL"X6S"
TOLERANCE"10%"
PACK_TYPE"C0402"
CDS_LIB"pure_quanta"
PART_NUMBER"CH5104KEB02"
LOCATION"C198"
$SEC"1"
CDS_SEC"1";
"B"
$PN"2"28;
"A"
$PN"1"37;
%"VCCAUX15"
"1","(-475,5250)","0","logical_power","I45";
;
HDL_POWER"P3V3_AUX"
CDS_LIB"logical_power";
"A"3;
%"UNIVERSAL_GND"
"1","(-475,4825)","0","logical_power","I46";
;
CDS_LIB"logical_power"
HDL_POWER"GND";
"A"26;
%"74LVC1G17GW"
"1","(-125,3250)","0","pure_quanta","I49";
;
PART_NUMBER"AL1G0017K01"
VALUE"74LVC1G17GW"
PART_TYPE"SMLF"
MATERIAL"IC"
CDS_LMAN_SYM_OUTLINE"-125,150,125,-150"
PIN_NAMES_ROTATE"True"
CDS_LIB"pure_quanta"
LOCATION"U32"
$SEC"1"
CDS_SEC"1";
"NC"
$PN"1"32;
"Y"
$PN"4"42;
"GND"
$PN"3"23;
"A"
$PN"2"38;
"VCC"
$PN"5"7;
%"VCCAUX15"
"1","(-450,3850)","0","logical_power","I50";
;
HDL_POWER"P3V3_AUX"
CDS_LIB"logical_power";
"A"7;
%"Q_CAP"
"1","(-450,3650)","2","pure_quanta","I51";
;
PART_NUMBER"CH4104K1B00"
VALUE"0.1UF"
PACK_TYPE"0402"
VOLTAGE"25V"
MATERIAL"X7R"
TOLERANCE"10%"
CDS_LIB"pure_quanta"
LOCATION"C201"
$SEC"1"
CDS_SEC"1";
"B"
$PN"2"25;
"A"
$PN"1"7;
%"UNIVERSAL_GND"
"1","(-450,3425)","0","logical_power","I52";
;
HDL_POWER"GND"
CDS_LIB"logical_power";
"A"25;
%"Q_CAP"
"1","(-1150,2975)","0","pure_quanta","I55";
;
PACK_TYPE"C0402"
VALUE"1UF"
VOLTAGE"25V"
MATERIAL"X6S"
TOLERANCE"10%"
PART_NUMBER"CH5104KEB02"
CDS_LIB"pure_quanta"
LOCATION"C199"
$SEC"1"
CDS_SEC"1";
"B"
$PN"2"23;
"A"
$PN"1"38;
%"Q_RES"
"2","(-1150,3625)","0","pure_quanta","I82";
;
PART_NUMBER"CS28202JB05"
PACK_TYPE"0402LF"
VALUE"8.2K"
TOLERANCE"5%"
WATTAGE"1/16W"
MATERIAL"CHIP"
CDS_LIB"pure_quanta"
LOCATION"R504"
$SEC"1"
CDS_SEC"1";
"A"
$PN"1"10;
"B"
$PN"2"38;
%"VCCAUX15"
"1","(-1150,3850)","0","logical_power","I83";
;
HDL_POWER"P3V3_AUX"
CDS_LIB"logical_power";
"A"10;
%"Q_RES"
"2","(-1175,5050)","0","pure_quanta","I89";
;
VALUE"8.2K"
PART_NUMBER"CS28202JB05"
WATTAGE"1/16W"
MATERIAL"CHIP"
TOLERANCE"5%"
PACK_TYPE"0402LF"
CDS_LIB"pure_quanta"
LOCATION"R768"
$SEC"1"
CDS_SEC"1";
"A"
$PN"1"4;
"B"
$PN"2"37;
%"VCCAUX15"
"1","(-1175,5250)","0","logical_power","I90";
;
HDL_POWER"P3V3_AUX"
CDS_LIB"logical_power";
"A"4;
END.
